# BASEBOARD_FAB2 (Tioga Pass) — schematic netlist excerpt (pin names and nets, part order shuffled) for the footprints in the layout excerpt that follows; sources: Cadence DE-HDL packaged netlist, KiCad conversion of Wiwynn_Tioga_Pass_MB.brd

R1U49  RES  2.7K 1% CHIP  pkg 0402  page 169 : A = P3V3_STBY ; B = FM_BATTERY_SENSE_EN
C5P16  CAP  47UF 4V 20% X6S  pkg 0805  page 42 : A = PVCCIN_CPU0 ; B = GND
SH4U2  SHUNT  EMPTY  pkg SH0201  page 217 : A = VSENSE_PVDDQ_ABC_P ; B = PVDDQ_ABC

(kicad_pcb
	(version 20260206)
	(generator "pcbnew")
	(generator_version "10.0")
	(general
		(thickness 1.6)
		(legacy_teardrops no)
	)
	(paper "A4")
	(title_block
		(title "Wiwynn_Tioga_Pass_MB.brd")
		(comment 1 "Tioga Pass / footprints 4297-4299 of 4770")
	)
	(layers
		(0 "F.Cu" signal "TOP")
		(4 "In1.Cu" signal "L2GND")
		(6 "In2.Cu" signal "L3")
		(8 "In3.Cu" signal "L4GND")
		(10 "In4.Cu" signal "L5")
		(12 "In5.Cu" signal "L6GND")
		(14 "In6.Cu" signal "L7VCC")
		(16 "In7.Cu" signal "L8VCC")
		(18 "In8.Cu" signal "L9GND")
		(20 "In9.Cu" signal "L10")
		(22 "In10.Cu" signal "L11GND")
		(24 "In11.Cu" signal "L12")
		(26 "In12.Cu" signal "L13GND")
		(2 "B.Cu" signal "BOTTOM")
		(9 "F.Adhes" user "F.Adhesive")
		(11 "B.Adhes" user "B.Adhesive")
		(13 "F.Paste" user "Package Geometry/Pastemask Top")
		(15 "B.Paste" user "Package Geometry/Pastemask Bottom")
		(5 "F.SilkS" user "Ref Des/Silkscreen Top")
		(7 "B.SilkS" user "Ref Des/Silkscreen Bottom")
		(1 "F.Mask" user "Board Geometry/Soldermask Top")
		(3 "B.Mask" user "Board Geometry/Soldermask Bottom")
		(17 "Dwgs.User" user "User.Drawings")
		(19 "Cmts.User" user "User.Comments")
		(21 "Eco1.User" user "User.Eco1")
		(23 "Eco2.User" user "User.Eco2")
		(25 "Edge.Cuts" user "Board Geometry/Outline")
		(27 "Margin" user)
		(31 "F.CrtYd" user "Package Geometry/Place Bound Top")
		(29 "B.CrtYd" user "Package Geometry/Place Bound Bottom")
		(35 "F.Fab" user "Ref Des/Assembly Top")
		(33 "B.Fab" user "Ref Des/Assembly Bottom")
	)
	(footprint ""
		(layer "B.Cu")
		(at 455.549 -4.2164 90)
		(property "Reference" "R1U49"
			(at 0 0 90)
			(layer "B.SilkS")
			(hide yes)
			(effects
				(font
					(size 1.27 1.27)
				)
				(justify mirror)
			)
		)
		(property "Value" ""
			(at 0 0 90)
			(layer "B.Fab")
			(effects
				(font
					(size 1.27 1.27)
				)
				(justify mirror)
			)
		)
		(duplicate_pad_numbers_are_jumpers no)
		(fp_poly
			(pts
				(xy 0.2794 -0.1016) (xy -0.2794 -0.1016) (xy -0.2794 0.9906) (xy 0.2794 0.9906)
			)
			(stroke
				(width 0)
				(type default)
			)
			(fill no)
			(layer "B.CrtYd")
		)
		(fp_line
			(start 0.2794 -0.1016)
			(end 0.2794 0.9906)
			(stroke
				(width 0.1)
				(type default)
			)
			(layer "B.Fab")
		)
		(fp_line
			(start -0.2794 -0.1016)
			(end 0.2794 -0.1016)
			(stroke
				(width 0.1)
				(type default)
			)
			(layer "B.Fab")
		)
		(fp_line
			(start 0.2794 0.9906)
			(end -0.2794 0.9906)
			(stroke
				(width 0.1)
				(type default)
			)
			(layer "B.Fab")
		)
		(fp_line
			(start -0.2794 0.9906)
			(end -0.2794 -0.1016)
			(stroke
				(width 0.1)
				(type default)
			)
			(layer "B.Fab")
		)
		(pad "1" smd rect
			(at 0 0 270)
			(size 0.508 0.508)
			(layers "B.Cu" "B.Mask" "B.Paste")
			(net "P3V3_STBY")
		)
		(pad "2" smd rect
			(at 0 0.889 270)
			(size 0.508 0.508)
			(layers "B.Cu" "B.Mask" "B.Paste")
			(net "FM_BATTERY_SENSE_EN")
		)
		(zone
			(layer "B.Cu")
			(hatch none 0.5)
			(connect_pads
				(clearance 0)
			)
			(min_thickness 0.25)
			(keepout
				(tracks allowed)
				(vias not_allowed)
				(pads allowed)
				(copperpour not_allowed)
				(footprints allowed)
			)
			(placement
				(enabled no)
				(sheetname "")
			)
			(fill
				(thermal_gap 0.5)
				(thermal_bridge_width 0.5)
				(island_removal_mode 0)
			)
			(polygon
				(pts
					(xy 455.803 -4.4704) (xy 455.803 -3.9624) (xy 456.184 -3.9624) (xy 456.184 -4.4704)
				)
			)
		)
		(zone
			(layer "B.Cu")
			(hatch none 0.5)
			(connect_pads
				(clearance 0)
			)
			(min_thickness 0.25)
			(keepout
				(tracks not_allowed)
				(vias allowed)
				(pads allowed)
				(copperpour not_allowed)
				(footprints allowed)
			)
			(placement
				(enabled no)
				(sheetname "")
			)
			(fill
				(thermal_gap 0.5)
				(thermal_bridge_width 0.5)
				(island_removal_mode 0)
			)
			(polygon
				(pts
					(xy 456.184 -4.4704) (xy 456.184 -3.9624) (xy 455.803 -3.9624) (xy 455.803 -4.4704)
				)
			)
		)
	)
	(footprint ""
		(layer "B.Cu")
		(at 276.0472 -29.337 -90)
		(property "Reference" "SH4U2"
			(at 0 0 90)
			(layer "B.SilkS")
			(hide yes)
			(effects
				(font
					(size 1.27 1.27)
				)
				(justify mirror)
			)
		)
		(property "Value" ""
			(at 0 0 90)
			(layer "B.Fab")
			(effects
				(font
					(size 1.27 1.27)
				)
				(justify mirror)
			)
		)
		(duplicate_pad_numbers_are_jumpers no)
		(fp_poly
			(pts
				(xy 0.1651 -0.0508) (xy 0.1651 0.5842) (xy -0.1651 0.5842) (xy -0.1651 -0.0508)
			)
			(stroke
				(width 0)
				(type default)
			)
			(fill no)
			(layer "B.CrtYd")
		)
		(fp_line
			(start -0.1651 0.5842)
			(end 0.1651 0.5842)
			(stroke
				(width 0.1)
				(type default)
			)
			(layer "B.Fab")
		)
		(fp_line
			(start 0.1651 0.5842)
			(end 0.1651 -0.0508)
			(stroke
				(width 0.1)
				(type default)
			)
			(layer "B.Fab")
		)
		(fp_line
			(start -0.1651 -0.0508)
			(end -0.1651 0.5842)
			(stroke
				(width 0.1)
				(type default)
			)
			(layer "B.Fab")
		)
		(fp_line
			(start 0.1651 -0.0508)
			(end -0.1651 -0.0508)
			(stroke
				(width 0.1)
				(type default)
			)
			(layer "B.Fab")
		)
		(pad "1" smd custom
			(at 0 0 270)
			(size 0.0762 0.0762)
			(layers "B.Cu" "B.Mask" "B.Paste")
			(net "VSENSE_PVDDQ_ABC_P")
			(options
				(clearance outline)
				(anchor circle)
			)
			(primitives
				(gr_poly
					(pts
						(arc
							(start -0.1524 0.10795)
							(mid -0.098518 0.130268)
							(end -0.0762 0.18415)
						)
						(xy -0.0762 0.22225) (xy 0.0762 0.22225)
						(arc
							(start 0.0762 0.18415)
							(mid 0.098518 0.130268)
							(end 0.1524 0.10795)
						)
						(xy 0.1524 -0.22225) (xy -0.1524 -0.22225)
					)
					(width 0)
					(fill yes)
				)
			)
		)
		(pad "2" smd custom
			(at 0 0.5334 90)
			(size 0.0762 0.0762)
			(layers "B.Cu" "B.Mask" "B.Paste")
			(net "PVDDQ_ABC")
			(options
				(clearance outline)
				(anchor circle)
			)
			(primitives
				(gr_poly
					(pts
						(arc
							(start -0.1524 0.10795)
							(mid -0.098518 0.130268)
							(end -0.0762 0.18415)
						)
						(xy -0.0762 0.22225) (xy 0.0762 0.22225)
						(arc
							(start 0.0762 0.18415)
							(mid 0.098518 0.130268)
							(end 0.1524 0.10795)
						)
						(xy 0.1524 -0.22225) (xy -0.1524 -0.22225)
					)
					(width 0)
					(fill yes)
				)
			)
		)
	)
	(footprint ""
		(layer "B.Cu")
		(at 264.416286 -79.60614 180)
		(property "Reference" "C5P16"
			(at 0 0 0)
			(layer "B.SilkS")
			(hide yes)
			(effects
				(font
					(size 1.27 1.27)
				)
				(justify mirror)
			)
		)
		(property "Value" ""
			(at 0 0 0)
			(layer "B.Fab")
			(effects
				(font
					(size 1.27 1.27)
				)
				(justify mirror)
			)
		)
		(duplicate_pad_numbers_are_jumpers no)
		(fp_poly
			(pts
				(xy 0.7239 -0.2159) (xy -0.7239 -0.2159) (xy -0.7239 1.9939) (xy 0.7239 1.9939)
			)
			(stroke
				(width 0)
				(type default)
			)
			(fill no)
			(layer "B.CrtYd")
		)
		(fp_line
			(start 0.7239 1.9939)
			(end -0.7239 1.9939)
			(stroke
				(width 0.1)
				(type default)
			)
			(layer "B.Fab")
		)
		(fp_line
			(start 0.7239 -0.2159)
			(end 0.7239 1.9939)
			(stroke
				(width 0.1)
				(type default)
			)
			(layer "B.Fab")
		)
		(fp_line
			(start -0.7239 1.9939)
			(end -0.7239 -0.2159)
			(stroke
				(width 0.1)
				(type default)
			)
			(layer "B.Fab")
		)
		(fp_line
			(start -0.7239 -0.2159)
			(end 0.7239 -0.2159)
			(stroke
				(width 0.1)
				(type default)
			)
			(layer "B.Fab")
		)
		(pad "1" smd rect
			(at 0 0)
			(size 1.27 1.016)
			(layers "B.Cu" "B.Mask" "B.Paste")
			(net "PVCCIN_CPU0")
		)
		(pad "2" smd rect
			(at 0 1.778)
			(size 1.27 1.016)
			(layers "B.Cu" "B.Mask" "B.Paste")
			(net "GND")
		)
		(zone
			(layer "B.Cu")
			(hatch none 0.5)
			(connect_pads
				(clearance 0)
			)
			(min_thickness 0.25)
			(keepout
				(tracks not_allowed)
				(vias allowed)
				(pads allowed)
				(copperpour not_allowed)
				(footprints allowed)
			)
			(placement
				(enabled no)
				(sheetname "")
			)
			(fill
				(thermal_gap 0.5)
				(thermal_bridge_width 0.5)
				(island_removal_mode 0)
			)
			(polygon
				(pts
					(xy 263.781286 -80.11414) (xy 265.051286 -80.11414) (xy 265.051286 -80.87614) (xy 263.781286 -80.87614)
				)
			)
		)
	)
)
